(kicad_pcb
	(version 20260206)
	(generator "pcbnew")
	(generator_version "10.0")
	(general
		(thickness 1.6)
		(legacy_teardrops no)
	)
	(paper "A4")
	(title_block
		(title "Bryce Canyon_R.DPB_16317-1_OCP.brd")
		(comment 1 "Bryce Canyon / footprints 1035-1039 of 2099")
	)
	(layers
		(0 "F.Cu" signal "TOP")
		(4 "In1.Cu" signal "L2GND")
		(6 "In2.Cu" signal "L3")
		(8 "In3.Cu" signal "L4VCC")
		(10 "In4.Cu" signal "L5VCC")
		(12 "In5.Cu" signal "L6")
		(14 "In6.Cu" signal "L7GND")
		(2 "B.Cu" signal "BOTTOM")
		(9 "F.Adhes" user "F.Adhesive")
		(11 "B.Adhes" user "B.Adhesive")
		(13 "F.Paste" user "Package Geometry/Pastemask Top")
		(15 "B.Paste" user "Package Geometry/Pastemask Bottom")
		(5 "F.SilkS" user "Ref Des/Silkscreen Top")
		(7 "B.SilkS" user "Ref Des/Silkscreen Bottom")
		(1 "F.Mask" user "Board Geometry/Soldermask Top")
		(3 "B.Mask" user "Board Geometry/Soldermask Bottom")
		(17 "Dwgs.User" user "User.Drawings")
		(19 "Cmts.User" user "User.Comments")
		(21 "Eco1.User" user "User.Eco1")
		(23 "Eco2.User" user "User.Eco2")
		(25 "Edge.Cuts" user "Board Geometry/Outline")
		(27 "Margin" user)
		(31 "F.CrtYd" user "Package Geometry/Place Bound Top")
		(29 "B.CrtYd" user "Package Geometry/Place Bound Bottom")
		(35 "F.Fab" user "Ref Des/Assembly Top")
		(33 "B.Fab" user "Ref Des/Assembly Bottom")
	)
	(footprint ""
		(layer "F.Cu")
		(at 237.871 -199.0852 90)
		(property "Reference" "U9"
			(at 0 0 90)
			(layer "F.SilkS")
			(hide yes)
			(effects
				(font
					(size 1.27 1.27)
				)
			)
		)
		(property "Value" "TCA9555PWR-GP"
			(at 0 -6.9342 90)
			(unlocked yes)
			(layer "F.Fab")
			(hide yes)
			(effects
				(font
					(size 1.016 1.016)
					(thickness 0.1524)
				)
			)
		)
		(property "Device Type" "TSOIC24H48"
			(at 0 -8.5852 90)
			(unlocked yes)
			(layer "F.Fab")
			(hide yes)
			(effects
				(font
					(size 1.016 1.016)
					(thickness 0.1524)
				)
			)
		)
		(duplicate_pad_numbers_are_jumpers no)
		(fp_line
			(start 3.81 -1.397)
			(end 3.81 1.397)
			(stroke
				(width 0.1524)
				(type default)
			)
			(layer "F.SilkS")
		)
		(fp_line
			(start -4.2291 -1.397)
			(end 3.81 -1.397)
			(stroke
				(width 0.1524)
				(type default)
			)
			(layer "F.SilkS")
		)
		(fp_line
			(start -4.2291 -0.8001)
			(end -3.429 0)
			(stroke
				(width 0.1524)
				(type default)
			)
			(layer "F.SilkS")
		)
		(fp_line
			(start -3.429 0)
			(end -4.2291 0.8001)
			(stroke
				(width 0.1524)
				(type default)
			)
			(layer "F.SilkS")
		)
		(fp_line
			(start 3.81 1.397)
			(end -4.2291 1.397)
			(stroke
				(width 0.1524)
				(type default)
			)
			(layer "F.SilkS")
		)
		(fp_line
			(start -4.22656 3.81)
			(end -4.2291 1.397)
			(stroke
				(width 0.508)
				(type default)
			)
			(layer "F.SilkS")
		)
		(fp_line
			(start -4.2291 3.937)
			(end -4.2291 -1.397)
			(stroke
				(width 0.1524)
				(type default)
			)
			(layer "F.SilkS")
		)
		(fp_poly
			(pts
				(xy -3.90652 -1.8542) (xy 3.90652 -1.8542) (xy 3.90652 1.8542) (xy -3.90652 1.8542)
			)
			(stroke
				(width 0)
				(type default)
			)
			(fill yes)
			(layer "F.SilkS")
		)
		(fp_poly
			(pts
				(xy -4.2164 3.81) (xy 4.2164 3.81) (xy 4.22656 -3.81) (xy -4.2164 -3.81)
			)
			(stroke
				(width 0)
				(type default)
			)
			(fill no)
			(layer "F.CrtYd")
		)
		(fp_poly
			(pts
				(xy -4.22656 -3.81) (xy 4.22656 -3.81) (xy 4.22656 3.81) (xy -4.22656 3.81)
			)
			(stroke
				(width 0)
				(type default)
			)
			(fill no)
			(layer "F.Fab")
		)
		(pad "1" smd rect
			(at -3.57632 2.8194 90)
			(size 0.3556 1.524)
			(layers "F.Cu" "F.Mask" "F.Paste")
			(net "IO_EXP2_INT_N")
		)
		(pad "2" smd rect
			(at -2.92608 2.8194 90)
			(size 0.3556 1.524)
			(layers "F.Cu" "F.Mask" "F.Paste")
			(net "IO_EXP2_A1")
		)
		(pad "3" smd rect
			(at -2.27584 2.8194 90)
			(size 0.3556 1.524)
			(layers "F.Cu" "F.Mask" "F.Paste")
			(net "IO_EXP2_A2")
		)
		(pad "4" smd rect
			(at -1.6256 2.8194 90)
			(size 0.3556 1.524)
			(layers "F.Cu" "F.Mask" "F.Paste")
			(net "DRIVE_B_16_PWR")
		)
		(pad "5" smd rect
			(at -0.97536 2.8194 90)
			(size 0.3556 1.524)
			(layers "F.Cu" "F.Mask" "F.Paste")
			(net "DRIVE_B_17_PWR")
		)
		(pad "6" smd rect
			(at -0.32512 2.8194 90)
			(size 0.3556 1.524)
			(layers "F.Cu" "F.Mask" "F.Paste")
			(net "DRIVE_B_18_PWR")
		)
		(pad "7" smd rect
			(at 0.32512 2.8194 90)
			(size 0.3556 1.524)
			(layers "F.Cu" "F.Mask" "F.Paste")
			(net "DRIVE_B_19_PWR")
		)
		(pad "8" smd rect
			(at 0.97536 2.8194 90)
			(size 0.3556 1.524)
			(layers "F.Cu" "F.Mask" "F.Paste")
			(net "DRIVE_B_20_PWR")
		)
		(pad "9" smd rect
			(at 1.6256 2.8194 90)
			(size 0.3556 1.524)
			(layers "F.Cu" "F.Mask" "F.Paste")
			(net "DRIVE_B_21_PWR")
		)
		(pad "10" smd rect
			(at 2.27584 2.8194 90)
			(size 0.3556 1.524)
			(layers "F.Cu" "F.Mask" "F.Paste")
			(net "DRIVE_B_22_PWR")
		)
		(pad "11" smd rect
			(at 2.92608 2.8194 90)
			(size 0.3556 1.524)
			(layers "F.Cu" "F.Mask" "F.Paste")
			(net "DRIVE_B_23_PWR")
		)
		(pad "12" smd rect
			(at 3.57632 2.8194 90)
			(size 0.3556 1.524)
			(layers "F.Cu" "F.Mask" "F.Paste")
			(net "GND")
		)
		(pad "13" smd rect
			(at 3.57632 -2.8194 90)
			(size 0.3556 1.524)
			(layers "F.Cu" "F.Mask" "F.Paste")
			(net "DRIVE_B_24_PWR")
		)
		(pad "14" smd rect
			(at 2.92608 -2.8194 90)
			(size 0.3556 1.524)
			(layers "F.Cu" "F.Mask" "F.Paste")
			(net "DRIVE_B_25_PWR")
		)
		(pad "15" smd rect
			(at 2.27584 -2.8194 90)
			(size 0.3556 1.524)
			(layers "F.Cu" "F.Mask" "F.Paste")
			(net "DRIVE_B_26_PWR")
		)
		(pad "16" smd rect
			(at 1.6256 -2.8194 90)
			(size 0.3556 1.524)
			(layers "F.Cu" "F.Mask" "F.Paste")
			(net "DRIVE_B_27_PWR")
		)
		(pad "17" smd rect
			(at 0.97536 -2.8194 90)
			(size 0.3556 1.524)
			(layers "F.Cu" "F.Mask" "F.Paste")
			(net "DRIVE_B_28_PWR")
		)
		(pad "18" smd rect
			(at 0.32512 -2.8194 90)
			(size 0.3556 1.524)
			(layers "F.Cu" "F.Mask" "F.Paste")
			(net "DRIVE_B_29_PWR")
		)
		(pad "19" smd rect
			(at -0.32512 -2.8194 90)
			(size 0.3556 1.524)
			(layers "F.Cu" "F.Mask" "F.Paste")
			(net "DRIVE_B_30_PWR")
		)
		(pad "20" smd rect
			(at -0.97536 -2.8194 90)
			(size 0.3556 1.524)
			(layers "F.Cu" "F.Mask" "F.Paste")
			(net "DRIVE_B_31_PWR")
		)
		(pad "21" smd rect
			(at -1.6256 -2.8194 90)
			(size 0.3556 1.524)
			(layers "F.Cu" "F.Mask" "F.Paste")
			(net "IO_EXP2_A0")
		)
		(pad "22" smd rect
			(at -2.27584 -2.8194 90)
			(size 0.3556 1.524)
			(layers "F.Cu" "F.Mask" "F.Paste")
			(net "IO_EXP2_SCL")
		)
		(pad "23" smd rect
			(at -2.92608 -2.8194 90)
			(size 0.3556 1.524)
			(layers "F.Cu" "F.Mask" "F.Paste")
			(net "IO_EXP2_SDA")
		)
		(pad "24" smd rect
			(at -3.57632 -2.8194 90)
			(size 0.3556 1.524)
			(layers "F.Cu" "F.Mask" "F.Paste")
			(net "GPIO_VCC_U9")
		)
	)
	(footprint ""
		(layer "F.Cu")
		(at 247.762522 -358.876346)
		(property "Reference" "C559"
			(at 0 0 0)
			(layer "F.SilkS")
			(hide yes)
			(effects
				(font
					(size 1.27 1.27)
				)
			)
		)
		(property "Value" "SCD1U25V2KX-2-GP"
			(at 1.1811 -2.7051 0)
			(unlocked yes)
			(layer "F.Fab")
			(hide yes)
			(effects
				(font
					(size 1.016 1.016)
					(thickness 0.1524)
				)
			)
		)
		(property "Device Type" "C402H22"
			(at 1.1811 -4.2291 0)
			(unlocked yes)
			(layer "F.Fab")
			(hide yes)
			(effects
				(font
					(size 1.016 1.016)
					(thickness 0.1524)
				)
			)
		)
		(duplicate_pad_numbers_are_jumpers no)
		(fp_rect
			(start -0.4318 0.9525)
			(end 0.4318 -0.9525)
			(stroke
				(width 0)
				(type default)
			)
			(fill no)
			(layer "F.CrtYd")
		)
		(fp_rect
			(start -0.4318 0.9525)
			(end 0.4318 -0.9525)
			(stroke
				(width 0)
				(type default)
			)
			(fill no)
			(layer "F.Fab")
		)
		(pad "1" smd custom
			(at 0 -0.4445)
			(size 0.1524 0.1524)
			(layers "F.Cu" "F.Mask" "F.Paste")
			(net "MB3_PSET_R")
			(options
				(clearance outline)
				(anchor circle)
			)
			(primitives
				(gr_poly
					(pts
						(arc
							(start 0.3048 -0.2032)
							(mid 0.275042 -0.275042)
							(end 0.2032 -0.3048)
						)
						(arc
							(start -0.2032 -0.3048)
							(mid -0.275042 -0.275042)
							(end -0.3048 -0.2032)
						)
						(arc
							(start -0.3048 0.2032)
							(mid -0.275042 0.275042)
							(end -0.2032 0.3048)
						)
						(arc
							(start 0.2032 0.3048)
							(mid 0.275042 0.275042)
							(end 0.3048 0.2032)
						)
					)
					(width 0)
					(fill yes)
				)
			)
		)
		(pad "2" smd custom
			(at 0 0.4445)
			(size 0.1524 0.1524)
			(layers "F.Cu" "F.Mask" "F.Paste")
			(net "AGND_CURRENT_DPB")
			(options
				(clearance outline)
				(anchor circle)
			)
			(primitives
				(gr_poly
					(pts
						(arc
							(start 0.3048 -0.2032)
							(mid 0.275042 -0.275042)
							(end 0.2032 -0.3048)
						)
						(arc
							(start -0.2032 -0.3048)
							(mid -0.275042 -0.275042)
							(end -0.3048 -0.2032)
						)
						(arc
							(start -0.3048 0.2032)
							(mid -0.275042 0.275042)
							(end -0.2032 0.3048)
						)
						(arc
							(start 0.2032 0.3048)
							(mid 0.275042 0.275042)
							(end 0.3048 0.2032)
						)
					)
					(width 0)
					(fill yes)
				)
			)
		)
	)
	(footprint ""
		(layer "F.Cu")
		(at 172.974 -133.096 180)
		(property "Reference" "R477"
			(at 0 0 180)
			(layer "F.SilkS")
			(hide yes)
			(effects
				(font
					(size 1.27 1.27)
				)
			)
		)
		(property "Value" "200KR2F-L-GP"
			(at 0.064008 -3.993896 180)
			(unlocked yes)
			(layer "F.Fab")
			(hide yes)
			(effects
				(font
					(size 1.016 1.016)
					(thickness 0.1524)
				)
			)
		)
		(property "Device Type" "R402H16"
			(at 0.064008 -5.517896 180)
			(unlocked yes)
			(layer "F.Fab")
			(hide yes)
			(effects
				(font
					(size 1.016 1.016)
					(thickness 0.1524)
				)
			)
		)
		(duplicate_pad_numbers_are_jumpers no)
		(fp_line
			(start 0.508 -0.9398)
			(end -0.508 -0.9398)
			(stroke
				(width 0.1524)
				(type default)
			)
			(layer "F.SilkS")
		)
		(fp_line
			(start -0.508 -0.9398)
			(end -0.508 0.9398)
			(stroke
				(width 0.1524)
				(type default)
			)
			(layer "F.SilkS")
		)
		(fp_rect
			(start -0.508 0.9398)
			(end 0.508 -0.9398)
			(stroke
				(width 0)
				(type default)
			)
			(fill no)
			(layer "F.CrtYd")
		)
		(fp_rect
			(start -0.508 0.9398)
			(end 0.508 -0.9398)
			(stroke
				(width 0)
				(type default)
			)
			(fill no)
			(layer "F.Fab")
		)
		(pad "1" smd custom
			(at 0 -0.4445 180)
			(size 0.1397 0.1397)
			(layers "F.Cu" "F.Mask" "F.Paste")
			(net "SW_HDD_R17")
			(options
				(clearance outline)
				(anchor circle)
			)
			(primitives
				(gr_poly
					(pts
						(arc
							(start -0.1778 -0.2794)
							(mid -0.249642 -0.249642)
							(end -0.2794 -0.1778)
						)
						(arc
							(start -0.2794 0.1778)
							(mid -0.249642 0.249642)
							(end -0.1778 0.2794)
						)
						(arc
							(start 0.1778 0.2794)
							(mid 0.249642 0.249642)
							(end 0.2794 0.1778)
						)
						(arc
							(start 0.2794 -0.1778)
							(mid 0.249642 -0.249642)
							(end 0.1778 -0.2794)
						)
					)
					(width 0)
					(fill yes)
				)
			)
		)
		(pad "2" smd custom
			(at 0 0.4445 180)
			(size 0.1397 0.1397)
			(layers "F.Cu" "F.Mask" "F.Paste")
			(net "SW_HDD_N17")
			(options
				(clearance outline)
				(anchor circle)
			)
			(primitives
				(gr_poly
					(pts
						(arc
							(start -0.1778 -0.2794)
							(mid -0.249642 -0.249642)
							(end -0.2794 -0.1778)
						)
						(arc
							(start -0.2794 0.1778)
							(mid -0.249642 0.249642)
							(end -0.1778 0.2794)
						)
						(arc
							(start 0.1778 0.2794)
							(mid 0.249642 0.249642)
							(end 0.2794 0.1778)
						)
						(arc
							(start 0.2794 -0.1778)
							(mid 0.249642 -0.249642)
							(end 0.1778 -0.2794)
						)
					)
					(width 0)
					(fill yes)
				)
			)
		)
	)
	(footprint ""
		(layer "F.Cu")
		(at 463.1436 -23.9776 90)
		(property "Reference" "D34"
			(at 0 0 90)
			(layer "F.SilkS")
			(hide yes)
			(effects
				(font
					(size 1.27 1.27)
				)
			)
		)
		(property "Value" "RB551V30-GP"
			(at 0 -6.7818 90)
			(unlocked yes)
			(layer "F.Fab")
			(hide yes)
			(effects
				(font
					(size 1.016 1.016)
					(thickness 0.1524)
				)
			)
		)
		(property "Device Type" "SOD323AKH38"
			(at 0 -8.6868 90)
			(unlocked yes)
			(layer "F.Fab")
			(hide yes)
			(effects
				(font
					(size 1.016 1.016)
					(thickness 0.1524)
				)
			)
		)
		(duplicate_pad_numbers_are_jumpers no)
		(fp_line
			(start 0.889 -1.9304)
			(end 0.889 2.159)
			(stroke
				(width 0.1524)
				(type default)
			)
			(layer "F.SilkS")
		)
		(fp_line
			(start -0.889 -1.9304)
			(end 0.889 -1.9304)
			(stroke
				(width 0.1524)
				(type default)
			)
			(layer "F.SilkS")
		)
		(fp_line
			(start 0.762 2.0574)
			(end -0.762 2.0574)
			(stroke
				(width 0.508)
				(type default)
			)
			(layer "F.SilkS")
		)
		(fp_line
			(start 0.889 2.159)
			(end -0.889 2.159)
			(stroke
				(width 0.1524)
				(type default)
			)
			(layer "F.SilkS")
		)
		(fp_line
			(start -0.889 2.159)
			(end -0.889 -1.9304)
			(stroke
				(width 0.1524)
				(type default)
			)
			(layer "F.SilkS")
		)
		(fp_rect
			(start -1.016 2.3114)
			(end 1.016 -2.0066)
			(stroke
				(width 0)
				(type default)
			)
			(fill no)
			(layer "F.CrtYd")
		)
		(fp_poly
			(pts
				(xy -1.016 -2.0066) (xy 1.016 -2.0066) (xy 1.016 2.3114) (xy -1.016 2.3114)
			)
			(stroke
				(width 0)
				(type default)
			)
			(fill no)
			(layer "F.Fab")
		)
		(pad "A" smd rect
			(at 0 -1.143 90)
			(size 0.5588 1.016)
			(layers "F.Cu" "F.Mask" "F.Paste")
			(net "SW_HDD_R34")
		)
		(pad "K" smd rect
			(at 0 1.143 90)
			(size 0.5588 1.016)
			(layers "F.Cu" "F.Mask" "F.Paste")
			(net "SW_HDD_N34")
		)
	)
	(footprint ""
		(layer "F.Cu")
		(at 141.097 -131.572 90)
		(property "Reference" "R452"
			(at 0 0 90)
			(layer "F.SilkS")
			(hide yes)
			(effects
				(font
					(size 1.27 1.27)
				)
			)
		)
		(property "Value" "4K7R2J-2-GP"
			(at 0.064008 -3.993896 90)
			(unlocked yes)
			(layer "F.Fab")
			(hide yes)
			(effects
				(font
					(size 1.016 1.016)
					(thickness 0.1524)
				)
			)
		)
		(property "Device Type" "R402H16"
			(at 0.064008 -5.517896 90)
			(unlocked yes)
			(layer "F.Fab")
			(hide yes)
			(effects
				(font
					(size 1.016 1.016)
					(thickness 0.1524)
				)
			)
		)
		(duplicate_pad_numbers_are_jumpers no)
		(fp_line
			(start 0.508 -0.9398)
			(end -0.508 -0.9398)
			(stroke
				(width 0.1524)
				(type default)
			)
			(layer "F.SilkS")
		)
		(fp_line
			(start -0.508 -0.9398)
			(end -0.508 0.9398)
			(stroke
				(width 0.1524)
				(type default)
			)
			(layer "F.SilkS")
		)
		(fp_rect
			(start -0.508 0.9398)
			(end 0.508 -0.9398)
			(stroke
				(width 0)
				(type default)
			)
			(fill no)
			(layer "F.CrtYd")
		)
		(fp_rect
			(start -0.508 0.9398)
			(end 0.508 -0.9398)
			(stroke
				(width 0)
				(type default)
			)
			(fill no)
			(layer "F.Fab")
		)
		(pad "1" smd custom
			(at 0 -0.4445 90)
			(size 0.1397 0.1397)
			(layers "F.Cu" "F.Mask" "F.Paste")
			(net "P12V_B")
			(options
				(clearance outline)
				(anchor circle)
			)
			(primitives
				(gr_poly
					(pts
						(arc
							(start -0.1778 -0.2794)
							(mid -0.249642 -0.249642)
							(end -0.2794 -0.1778)
						)
						(arc
							(start -0.2794 0.1778)
							(mid -0.249642 0.249642)
							(end -0.1778 0.2794)
						)
						(arc
							(start 0.1778 0.2794)
							(mid 0.249642 0.249642)
							(end 0.2794 0.1778)
						)
						(arc
							(start 0.2794 -0.1778)
							(mid 0.249642 -0.249642)
							(end 0.1778 -0.2794)
						)
					)
					(width 0)
					(fill yes)
				)
			)
		)
		(pad "2" smd custom
			(at 0 0.4445 90)
			(size 0.1397 0.1397)
			(layers "F.Cu" "F.Mask" "F.Paste")
			(net "SW_HDD_R16")
			(options
				(clearance outline)
				(anchor circle)
			)
			(primitives
				(gr_poly
					(pts
						(arc
							(start -0.1778 -0.2794)
							(mid -0.249642 -0.249642)
							(end -0.2794 -0.1778)
						)
						(arc
							(start -0.2794 0.1778)
							(mid -0.249642 0.249642)
							(end -0.1778 0.2794)
						)
						(arc
							(start 0.1778 0.2794)
							(mid 0.249642 0.249642)
							(end 0.2794 0.1778)
						)
						(arc
							(start 0.2794 -0.1778)
							(mid 0.249642 -0.249642)
							(end 0.1778 -0.2794)
						)
					)
					(width 0)
					(fill yes)
				)
			)
		)
	)
)
